# TIMECARD (Time Appliance Project (Time Card)) — schematic netlist excerpt (pin names and nets, part order shuffled) for the footprints in the layout excerpt that follows; sources: Cadence DE-HDL packaged netlist, KiCad conversion of R4006-B0001-02_R01.brd

R368  RESISTOR  4.7KOHM 1%  pkg SMC_0402R_H016  page 23 : \1\ = XP3R3V_FPGA ; \2\ = SMA4_SIG_OUT_BF_EN_N
R255  RESISTOR  22.6K 1%  pkg SMC_0402R_H016  page 29 : \1\ = UNNAMED_523_CAPACITOR_I28_1 ; \2\ = XP1R0V_FB_R_TO_AGND

(kicad_pcb
	(version 20260206)
	(generator "pcbnew")
	(generator_version "10.0")
	(general
		(thickness 1.6)
		(legacy_teardrops no)
	)
	(paper "A4")
	(title_block
		(title "timecard-production-celestica-r4006 — R4006-B0001-02_R01.brd")
		(comment 1 "Time Appliance Project (Time Card) / footprints 284-285 of 1113")
	)
	(layers
		(0 "F.Cu" signal "TOP")
		(4 "In1.Cu" signal "L02_GND1")
		(6 "In2.Cu" signal "L03_SIG1")
		(8 "In3.Cu" signal "L04_GND2")
		(10 "In4.Cu" signal "L05_VCC1")
		(12 "In5.Cu" signal "L06_VCC2")
		(14 "In6.Cu" signal "L07_GND3")
		(16 "In7.Cu" signal "L08_SIG2")
		(18 "In8.Cu" signal "L09_GND4")
		(2 "B.Cu" signal "BOTTOM")
		(9 "F.Adhes" user "F.Adhesive")
		(11 "B.Adhes" user "B.Adhesive")
		(13 "F.Paste" user "Package Geometry/Pastemask Top")
		(15 "B.Paste" user "Package Geometry/Pastemask Bottom")
		(5 "F.SilkS" user "Ref Des/Silkscreen Top")
		(7 "B.SilkS" user "Ref Des/Silkscreen Bottom")
		(1 "F.Mask" user "Board Geometry/Soldermask Top")
		(3 "B.Mask" user "Board Geometry/Soldermask Bottom")
		(17 "Dwgs.User" user "User.Drawings")
		(19 "Cmts.User" user "User.Comments")
		(21 "Eco1.User" user "User.Eco1")
		(23 "Eco2.User" user "User.Eco2")
		(25 "Edge.Cuts" user "Board Geometry/Outline")
		(27 "Margin" user)
		(31 "F.CrtYd" user "Package Geometry/Place Bound Top")
		(29 "B.CrtYd" user "Package Geometry/Place Bound Bottom")
		(35 "F.Fab" user "Ref Des/Assembly Top")
		(33 "B.Fab" user "Ref Des/Assembly Bottom")
	)
	(footprint ""
		(layer "F.Cu")
		(at 146.1516 -59.563 -90)
		(property "Reference" "R255"
			(at 1.016 -1.84277 90)
			(unlocked yes)
			(layer "F.SilkS")
			(effects
				(font
					(size 0.7874 0.5842)
					(thickness 0.1524)
				)
			)
		)
		(property "Value" "VAL*"
			(at 0.02032 2.13233 270)
			(unlocked yes)
			(layer "F.Fab")
			(hide yes)
			(effects
				(font
					(size 0.7874 0.5842)
					(thickness 0.1524)
				)
			)
		)
		(property "Device Type" "RESISTOR-G155-02262-01,22.6K,1%"
			(at 0.008382 1.210564 270)
			(unlocked yes)
			(layer "F.Fab")
			(hide yes)
			(effects
				(font
					(size 0.7874 0.5842)
					(thickness 0.1524)
				)
			)
		)
		(property "User Part Number" "PARTNUM*"
			(at 0.02032 4.024884 270)
			(unlocked yes)
			(layer "Cmts.User")
			(hide yes)
			(effects
				(font
					(size 0.7874 0.5842)
					(thickness 0.1524)
				)
			)
		)
		(property "Tolerance" "TOL*"
			(at 0.044704 3.05435 270)
			(unlocked yes)
			(layer "Cmts.User")
			(hide yes)
			(effects
				(font
					(size 0.7874 0.5842)
					(thickness 0.1524)
				)
			)
		)
		(duplicate_pad_numbers_are_jumpers no)
		(fp_line
			(start -1.143 0.5588)
			(end 1.143 0.5588)
			(stroke
				(width 0.1)
				(type default)
			)
			(layer "F.SilkS")
		)
		(fp_line
			(start 1.143 0.5588)
			(end 1.143 -0.5588)
			(stroke
				(width 0.1)
				(type default)
			)
			(layer "F.SilkS")
		)
		(fp_line
			(start -1.143 -0.5588)
			(end -1.143 0.5588)
			(stroke
				(width 0.1)
				(type default)
			)
			(layer "F.SilkS")
		)
		(fp_line
			(start 1.143 -0.5588)
			(end -1.143 -0.5588)
			(stroke
				(width 0.1)
				(type default)
			)
			(layer "F.SilkS")
		)
		(fp_rect
			(start 1.143 0.5588)
			(end -1.143 -0.5588)
			(stroke
				(width 0)
				(type default)
			)
			(fill no)
			(layer "F.CrtYd")
		)
		(fp_line
			(start -0.508 0.3048)
			(end 0.508 0.3048)
			(stroke
				(width 0.1)
				(type default)
			)
			(layer "F.Fab")
		)
		(fp_line
			(start 0.508 0.3048)
			(end 0.508 -0.3048)
			(stroke
				(width 0.1)
				(type default)
			)
			(layer "F.Fab")
		)
		(fp_line
			(start -0.508 -0.3048)
			(end -0.508 0.3048)
			(stroke
				(width 0.1)
				(type default)
			)
			(layer "F.Fab")
		)
		(fp_line
			(start 0.508 -0.3048)
			(end -0.508 -0.3048)
			(stroke
				(width 0.1)
				(type default)
			)
			(layer "F.Fab")
		)
		(pad "1" smd rect
			(at -0.5334 0 270)
			(size 0.7112 0.6096)
			(layers "F.Cu" "F.Mask" "F.Paste")
			(net "UNNAMED_523_CAPACITOR_I28_1")
		)
		(pad "2" smd rect
			(at 0.5334 0 270)
			(size 0.7112 0.6096)
			(layers "F.Cu" "F.Mask" "F.Paste")
			(net "XP1R0V_FB_R_TO_AGND")
		)
		(zone
			(layer "F.Cu")
			(hatch none 0.5)
			(connect_pads
				(clearance 0)
			)
			(min_thickness 0.25)
			(keepout
				(tracks allowed)
				(vias not_allowed)
				(pads allowed)
				(copperpour not_allowed)
				(footprints allowed)
			)
			(placement
				(enabled no)
				(sheetname "")
			)
			(fill
				(thermal_gap 0.5)
				(thermal_bridge_width 0.5)
				(island_removal_mode 0)
			)
			(polygon
				(pts
					(xy 145.8468 -59.4868) (xy 146.4564 -59.4868) (xy 146.4564 -59.6392) (xy 145.8468 -59.6392)
				)
			)
		)
	)
	(footprint ""
		(layer "F.Cu")
		(at 14.732 -22.987 -90)
		(property "Reference" "R368"
			(at 0.635 3.64363 90)
			(unlocked yes)
			(layer "F.SilkS")
			(effects
				(font
					(size 0.7874 0.5842)
					(thickness 0.1524)
				)
			)
		)
		(property "Value" "VAL*"
			(at 0.02032 2.13233 270)
			(unlocked yes)
			(layer "F.Fab")
			(hide yes)
			(effects
				(font
					(size 0.7874 0.5842)
					(thickness 0.1524)
				)
			)
		)
		(property "Tolerance" "TOL*"
			(at 0.044704 3.05435 270)
			(unlocked yes)
			(layer "Cmts.User")
			(hide yes)
			(effects
				(font
					(size 0.7874 0.5842)
					(thickness 0.1524)
				)
			)
		)
		(property "User Part Number" "PARTNUM*"
			(at 0.02032 4.024884 270)
			(unlocked yes)
			(layer "Cmts.User")
			(hide yes)
			(effects
				(font
					(size 0.7874 0.5842)
					(thickness 0.1524)
				)
			)
		)
		(property "Device Type" "RESISTOR-G155-14701-01,4.7KOHMA"
			(at 0.008382 1.210564 270)
			(unlocked yes)
			(layer "F.Fab")
			(hide yes)
			(effects
				(font
					(size 0.7874 0.5842)
					(thickness 0.1524)
				)
			)
		)
		(duplicate_pad_numbers_are_jumpers no)
		(fp_line
			(start -1.143 0.5588)
			(end 1.143 0.5588)
			(stroke
				(width 0.1)
				(type default)
			)
			(layer "F.SilkS")
		)
		(fp_line
			(start 1.143 0.5588)
			(end 1.143 -0.5588)
			(stroke
				(width 0.1)
				(type default)
			)
			(layer "F.SilkS")
		)
		(fp_line
			(start -1.143 -0.5588)
			(end -1.143 0.5588)
			(stroke
				(width 0.1)
				(type default)
			)
			(layer "F.SilkS")
		)
		(fp_line
			(start 1.143 -0.5588)
			(end -1.143 -0.5588)
			(stroke
				(width 0.1)
				(type default)
			)
			(layer "F.SilkS")
		)
		(fp_rect
			(start -1.143 0.5588)
			(end 1.143 -0.5588)
			(stroke
				(width 0)
				(type default)
			)
			(fill no)
			(layer "F.CrtYd")
		)
		(fp_line
			(start -0.508 0.3048)
			(end 0.508 0.3048)
			(stroke
				(width 0.1)
				(type default)
			)
			(layer "F.Fab")
		)
		(fp_line
			(start 0.508 0.3048)
			(end 0.508 -0.3048)
			(stroke
				(width 0.1)
				(type default)
			)
			(layer "F.Fab")
		)
		(fp_line
			(start -0.508 -0.3048)
			(end -0.508 0.3048)
			(stroke
				(width 0.1)
				(type default)
			)
			(layer "F.Fab")
		)
		(fp_line
			(start 0.508 -0.3048)
			(end -0.508 -0.3048)
			(stroke
				(width 0.1)
				(type default)
			)
			(layer "F.Fab")
		)
		(pad "1" smd rect
			(at -0.5334 0 270)
			(size 0.7112 0.6096)
			(layers "F.Cu" "F.Mask" "F.Paste")
			(net "XP3R3V_FPGA")
		)
		(pad "2" smd rect
			(at 0.5334 0 270)
			(size 0.7112 0.6096)
			(layers "F.Cu" "F.Mask" "F.Paste")
			(net "SMA4_SIG_OUT_BF_EN_N")
		)
		(zone
			(layer "F.Cu")
			(hatch none 0.5)
			(connect_pads
				(clearance 0)
			)
			(min_thickness 0.25)
			(keepout
				(tracks not_allowed)
				(vias allowed)
				(pads allowed)
				(copperpour not_allowed)
				(footprints allowed)
			)
			(placement
				(enabled no)
				(sheetname "")
			)
			(fill
				(thermal_gap 0.5)
				(thermal_bridge_width 0.5)
				(island_removal_mode 0)
			)
			(polygon
				(pts
					(xy 14.4272 -23.0632) (xy 14.4272 -22.9108) (xy 15.0368 -22.9108) (xy 15.0368 -23.0632)
				)
			)
		)
		(zone
			(layer "F.Cu")
			(hatch none 0.5)
			(connect_pads
				(clearance 0)
			)
			(min_thickness 0.25)
			(keepout
				(tracks allowed)
				(vias not_allowed)
				(pads allowed)
				(copperpour not_allowed)
				(footprints allowed)
			)
			(placement
				(enabled no)
				(sheetname "")
			)
			(fill
				(thermal_gap 0.5)
				(thermal_bridge_width 0.5)
				(island_removal_mode 0)
			)
			(polygon
				(pts
					(xy 14.4272 -23.0632) (xy 14.4272 -22.9108) (xy 15.0368 -22.9108) (xy 15.0368 -23.0632)
				)
			)
		)
	)
)
